# BASEBOARD_FAB2 (Tioga Pass) — schematic netlist excerpt (pin names and nets, part order shuffled) for the footprints in the layout excerpt that follows; sources: Cadence DE-HDL packaged netlist, KiCad conversion of Wiwynn_Tioga_Pass_MB.brd

C5G41  CAP_A  22.0UF 4V 20% X6S  pkg 0603V  page 242 : A = PVDDQ_ABC ; B = GND
R1L12  RES  0.0 5% CHIP  pkg 0402  page 175 : A = PWRGD_P3V3 ; B = PWRGD_P3V3_R
C2M19  CAP_A  1.0UF 6.3V 10% X6S  pkg 0402V  page 131 : A = P1V05_PCH_STBY ; B = GND

(kicad_pcb
	(version 20260206)
	(generator "pcbnew")
	(generator_version "10.0")
	(general
		(thickness 1.6)
		(legacy_teardrops no)
	)
	(paper "A4")
	(title_block
		(title "Wiwynn_Tioga_Pass_MB.brd")
		(comment 1 "Tioga Pass / footprints 4170-4172 of 4770")
	)
	(layers
		(0 "F.Cu" signal "TOP")
		(4 "In1.Cu" signal "L2GND")
		(6 "In2.Cu" signal "L3")
		(8 "In3.Cu" signal "L4GND")
		(10 "In4.Cu" signal "L5")
		(12 "In5.Cu" signal "L6GND")
		(14 "In6.Cu" signal "L7VCC")
		(16 "In7.Cu" signal "L8VCC")
		(18 "In8.Cu" signal "L9GND")
		(20 "In9.Cu" signal "L10")
		(22 "In10.Cu" signal "L11GND")
		(24 "In11.Cu" signal "L12")
		(26 "In12.Cu" signal "L13GND")
		(2 "B.Cu" signal "BOTTOM")
		(9 "F.Adhes" user "F.Adhesive")
		(11 "B.Adhes" user "B.Adhesive")
		(13 "F.Paste" user "Package Geometry/Pastemask Top")
		(15 "B.Paste" user "Package Geometry/Pastemask Bottom")
		(5 "F.SilkS" user "Ref Des/Silkscreen Top")
		(7 "B.SilkS" user "Ref Des/Silkscreen Bottom")
		(1 "F.Mask" user "Board Geometry/Soldermask Top")
		(3 "B.Mask" user "Board Geometry/Soldermask Bottom")
		(17 "Dwgs.User" user "User.Drawings")
		(19 "Cmts.User" user "User.Comments")
		(21 "Eco1.User" user "User.Eco1")
		(23 "Eco2.User" user "User.Eco2")
		(25 "Edge.Cuts" user "Board Geometry/Outline")
		(27 "Margin" user)
		(31 "F.CrtYd" user "Package Geometry/Place Bound Top")
		(29 "B.CrtYd" user "Package Geometry/Place Bound Bottom")
		(35 "F.Fab" user "Ref Des/Assembly Top")
		(33 "B.Fab" user "Ref Des/Assembly Bottom")
	)
	(footprint ""
		(layer "B.Cu")
		(at 389.33755 -114.25555 180)
		(property "Reference" "C2M19"
			(at 0 0 0)
			(layer "B.SilkS")
			(hide yes)
			(effects
				(font
					(size 1.27 1.27)
				)
				(justify mirror)
			)
		)
		(property "Value" ""
			(at 0 0 0)
			(layer "B.Fab")
			(effects
				(font
					(size 1.27 1.27)
				)
				(justify mirror)
			)
		)
		(duplicate_pad_numbers_are_jumpers no)
		(fp_rect
			(start 0.2794 0.9144)
			(end -0.2794 -0.1143)
			(stroke
				(width 0)
				(type default)
			)
			(fill no)
			(layer "B.CrtYd")
		)
		(fp_line
			(start 0.2794 0.9144)
			(end 0.2794 -0.1143)
			(stroke
				(width 0.1)
				(type default)
			)
			(layer "B.Fab")
		)
		(fp_line
			(start 0.2794 -0.1143)
			(end -0.2794 -0.1143)
			(stroke
				(width 0.1)
				(type default)
			)
			(layer "B.Fab")
		)
		(fp_line
			(start -0.2794 0.9144)
			(end 0.2794 0.9144)
			(stroke
				(width 0.1)
				(type default)
			)
			(layer "B.Fab")
		)
		(fp_line
			(start -0.2794 -0.1143)
			(end -0.2794 0.9144)
			(stroke
				(width 0.1)
				(type default)
			)
			(layer "B.Fab")
		)
		(pad "1" smd custom
			(at 0 0 90)
			(size 0.10414 0.10414)
			(layers "B.Cu" "B.Mask" "B.Paste")
			(net "P1V05_PCH_STBY")
			(options
				(clearance outline)
				(anchor circle)
			)
			(primitives
				(gr_poly
					(pts
						(xy -0.20828 -0.08636) (xy -0.20828 0.08636) (xy -0.08636 0.20828) (xy 0.086614 0.20828) (xy 0.20828 0.086614)
						(xy 0.20828 -0.08636) (xy 0.08636 -0.20828) (xy -0.08636 -0.20828)
					)
					(width 0)
					(fill yes)
				)
			)
		)
		(pad "2" smd custom
			(at 0 0.8001 90)
			(size 0.10414 0.10414)
			(layers "B.Cu" "B.Mask" "B.Paste")
			(net "GND")
			(options
				(clearance outline)
				(anchor circle)
			)
			(primitives
				(gr_poly
					(pts
						(xy -0.20828 -0.08636) (xy -0.20828 0.08636) (xy -0.08636 0.20828) (xy 0.086614 0.20828) (xy 0.20828 0.086614)
						(xy 0.20828 -0.08636) (xy 0.08636 -0.20828) (xy -0.08636 -0.20828)
					)
					(width 0)
					(fill yes)
				)
			)
		)
		(zone
			(layer "B.Cu")
			(hatch none 0.5)
			(connect_pads
				(clearance 0)
			)
			(min_thickness 0.25)
			(keepout
				(tracks allowed)
				(vias not_allowed)
				(pads allowed)
				(copperpour not_allowed)
				(footprints allowed)
			)
			(placement
				(enabled no)
				(sheetname "")
			)
			(fill
				(thermal_gap 0.5)
				(thermal_bridge_width 0.5)
				(island_removal_mode 0)
			)
			(polygon
				(pts
					(xy 389.24992 -114.4651) (xy 389.24992 -114.8461) (xy 389.42518 -114.8461) (xy 389.425434 -114.4651)
				)
			)
		)
		(zone
			(layer "B.Cu")
			(hatch none 0.5)
			(connect_pads
				(clearance 0)
			)
			(min_thickness 0.25)
			(keepout
				(tracks not_allowed)
				(vias allowed)
				(pads allowed)
				(copperpour not_allowed)
				(footprints allowed)
			)
			(placement
				(enabled no)
				(sheetname "")
			)
			(fill
				(thermal_gap 0.5)
				(thermal_bridge_width 0.5)
				(island_removal_mode 0)
			)
			(polygon
				(pts
					(xy 389.24992 -114.4651) (xy 389.24992 -114.8461) (xy 389.42518 -114.8461) (xy 389.425434 -114.4651)
				)
			)
		)
	)
	(footprint ""
		(layer "B.Cu")
		(at 490.5375 -155.3337 -90)
		(property "Reference" "R1L12"
			(at 0 0 90)
			(layer "B.SilkS")
			(hide yes)
			(effects
				(font
					(size 1.27 1.27)
				)
				(justify mirror)
			)
		)
		(property "Value" ""
			(at 0 0 90)
			(layer "B.Fab")
			(effects
				(font
					(size 1.27 1.27)
				)
				(justify mirror)
			)
		)
		(duplicate_pad_numbers_are_jumpers no)
		(fp_poly
			(pts
				(xy 0.2794 -0.1016) (xy -0.2794 -0.1016) (xy -0.2794 0.9906) (xy 0.2794 0.9906)
			)
			(stroke
				(width 0)
				(type default)
			)
			(fill no)
			(layer "B.CrtYd")
		)
		(fp_line
			(start -0.2794 0.9906)
			(end -0.2794 -0.1016)
			(stroke
				(width 0.1)
				(type default)
			)
			(layer "B.Fab")
		)
		(fp_line
			(start 0.2794 0.9906)
			(end -0.2794 0.9906)
			(stroke
				(width 0.1)
				(type default)
			)
			(layer "B.Fab")
		)
		(fp_line
			(start -0.2794 -0.1016)
			(end 0.2794 -0.1016)
			(stroke
				(width 0.1)
				(type default)
			)
			(layer "B.Fab")
		)
		(fp_line
			(start 0.2794 -0.1016)
			(end 0.2794 0.9906)
			(stroke
				(width 0.1)
				(type default)
			)
			(layer "B.Fab")
		)
		(pad "1" smd rect
			(at 0 0 90)
			(size 0.508 0.508)
			(layers "B.Cu" "B.Mask" "B.Paste")
			(net "PWRGD_P3V3")
		)
		(pad "2" smd rect
			(at 0 0.889 90)
			(size 0.508 0.508)
			(layers "B.Cu" "B.Mask" "B.Paste")
			(net "PWRGD_P3V3_R")
		)
		(zone
			(layer "B.Cu")
			(hatch none 0.5)
			(connect_pads
				(clearance 0)
			)
			(min_thickness 0.25)
			(keepout
				(tracks not_allowed)
				(vias allowed)
				(pads allowed)
				(copperpour not_allowed)
				(footprints allowed)
			)
			(placement
				(enabled no)
				(sheetname "")
			)
			(fill
				(thermal_gap 0.5)
				(thermal_bridge_width 0.5)
				(island_removal_mode 0)
			)
			(polygon
				(pts
					(xy 489.9025 -155.0797) (xy 489.9025 -155.5877) (xy 490.2835 -155.5877) (xy 490.2835 -155.0797)
				)
			)
		)
		(zone
			(layer "B.Cu")
			(hatch none 0.5)
			(connect_pads
				(clearance 0)
			)
			(min_thickness 0.25)
			(keepout
				(tracks allowed)
				(vias not_allowed)
				(pads allowed)
				(copperpour not_allowed)
				(footprints allowed)
			)
			(placement
				(enabled no)
				(sheetname "")
			)
			(fill
				(thermal_gap 0.5)
				(thermal_bridge_width 0.5)
				(island_removal_mode 0)
			)
			(polygon
				(pts
					(xy 490.2835 -155.0797) (xy 490.2835 -155.5877) (xy 489.9025 -155.5877) (xy 489.9025 -155.0797)
				)
			)
		)
	)
	(footprint ""
		(layer "B.Cu")
		(at 245.7069 -12.954 -90)
		(property "Reference" "C5G41"
			(at -1.14681 0.76708 0)
			(unlocked yes)
			(layer "B.SilkS")
			(effects
				(font
					(size 0.7874 0.5842)
					(thickness 0.1524)
				)
				(justify mirror)
			)
		)
		(property "Value" ""
			(at 0 0 90)
			(layer "B.Fab")
			(effects
				(font
					(size 1.27 1.27)
				)
				(justify mirror)
			)
		)
		(duplicate_pad_numbers_are_jumpers no)
		(fp_rect
			(start 0.4953 1.6002)
			(end -0.4953 -0.2032)
			(stroke
				(width 0)
				(type default)
			)
			(fill no)
			(layer "B.CrtYd")
		)
		(fp_line
			(start -0.4953 1.6002)
			(end 0.4953 1.6002)
			(stroke
				(width 0.1)
				(type default)
			)
			(layer "B.Fab")
		)
		(fp_line
			(start 0.4953 1.6002)
			(end 0.4953 -0.2032)
			(stroke
				(width 0.1)
				(type default)
			)
			(layer "B.Fab")
		)
		(fp_line
			(start -0.4953 -0.2032)
			(end -0.4953 1.6002)
			(stroke
				(width 0.1)
				(type default)
			)
			(layer "B.Fab")
		)
		(fp_line
			(start 0.4953 -0.2032)
			(end -0.4953 -0.2032)
			(stroke
				(width 0.1)
				(type default)
			)
			(layer "B.Fab")
		)
		(pad "1" smd rect
			(at 0 0 90)
			(size 0.762 0.889)
			(layers "B.Cu" "B.Mask" "B.Paste")
			(net "PVDDQ_ABC")
		)
		(pad "2" smd rect
			(at 0 1.397 90)
			(size 0.762 0.889)
			(layers "B.Cu" "B.Mask" "B.Paste")
			(net "GND")
		)
		(zone
			(layer "B.Cu")
			(hatch none 0.5)
			(connect_pads
				(clearance 0)
			)
			(min_thickness 0.25)
			(keepout
				(tracks not_allowed)
				(vias allowed)
				(pads allowed)
				(copperpour not_allowed)
				(footprints allowed)
			)
			(placement
				(enabled no)
				(sheetname "")
			)
			(fill
				(thermal_gap 0.5)
				(thermal_bridge_width 0.5)
				(island_removal_mode 0)
			)
			(polygon
				(pts
					(xy 244.7544 -12.573) (xy 245.2624 -12.573) (xy 245.2624 -13.335) (xy 244.7544 -13.335)
				)
			)
		)
	)
)
